(kicad_pcb
	(version 20260206)
	(generator "pcbnew")
	(generator_version "10.0")
	(general
		(thickness 1.6)
		(legacy_teardrops no)
	)
	(paper "A4")
	(title_block
		(title "04192023_DAF0TMB3IC0_F0TG_MB_C_brd_V02_OCP.brd")
		(comment 1 "Grand Teton / footprints 7734-7740 of 8354")
	)
	(layers
		(0 "F.Cu" signal "TOP")
		(4 "In1.Cu" signal "GND")
		(6 "In2.Cu" signal "IN1")
		(8 "In3.Cu" signal "GND1")
		(10 "In4.Cu" signal "IN2")
		(12 "In5.Cu" signal "GND2")
		(14 "In6.Cu" signal "IN3")
		(16 "In7.Cu" signal "GND3")
		(18 "In8.Cu" signal "VCC")
		(20 "In9.Cu" signal "VCC1")
		(22 "In10.Cu" signal "GND4")
		(24 "In11.Cu" signal "IN4")
		(26 "In12.Cu" signal "GND5")
		(28 "In13.Cu" signal "IN5")
		(30 "In14.Cu" signal "GND6")
		(32 "In15.Cu" signal "IN6")
		(34 "In16.Cu" signal "GND7")
		(2 "B.Cu" signal "BOTTOM")
		(9 "F.Adhes" user "F.Adhesive")
		(11 "B.Adhes" user "B.Adhesive")
		(13 "F.Paste" user "Package Geometry/Pastemask Top")
		(15 "B.Paste" user "Package Geometry/Pastemask Bottom")
		(5 "F.SilkS" user "Ref Des/Silkscreen Top")
		(7 "B.SilkS" user "Ref Des/Silkscreen Bottom")
		(1 "F.Mask" user "Board Geometry/Soldermask Top")
		(3 "B.Mask" user "Board Geometry/Soldermask Bottom")
		(17 "Dwgs.User" user "User.Drawings")
		(19 "Cmts.User" user "User.Comments")
		(21 "Eco1.User" user "User.Eco1")
		(23 "Eco2.User" user "User.Eco2")
		(25 "Edge.Cuts" user "Board Geometry/Outline")
		(27 "Margin" user)
		(31 "F.CrtYd" user "Package Geometry/Place Bound Top")
		(29 "B.CrtYd" user "Package Geometry/Place Bound Bottom")
		(35 "F.Fab" user "Ref Des/Assembly Top")
		(33 "B.Fab" user "Ref Des/Assembly Bottom")
	)
	(footprint ""
		(layer "B.Cu")
		(at 52.881022 -244.085364 180)
		(property "Reference" "R501"
			(at 0 0 0)
			(layer "B.SilkS")
			(hide yes)
			(effects
				(font
					(size 1.27 1.27)
				)
				(justify mirror)
			)
		)
		(property "Value" ""
			(at 0 0 0)
			(layer "B.Fab")
			(effects
				(font
					(size 1.27 1.27)
				)
				(justify mirror)
			)
		)
		(duplicate_pad_numbers_are_jumpers no)
		(fp_line
			(start 0.7874 0.4064)
			(end 0.7874 -0.4064)
			(stroke
				(width 0.1524)
				(type default)
			)
			(layer "B.SilkS")
		)
		(fp_line
			(start 0.7874 -0.4064)
			(end -0.7874 -0.4064)
			(stroke
				(width 0.1524)
				(type default)
			)
			(layer "B.SilkS")
		)
		(fp_line
			(start -0.7874 0.4064)
			(end 0.7874 0.4064)
			(stroke
				(width 0.1524)
				(type default)
			)
			(layer "B.SilkS")
		)
		(fp_line
			(start -0.7874 -0.4064)
			(end -0.7874 0.4064)
			(stroke
				(width 0.1524)
				(type default)
			)
			(layer "B.SilkS")
		)
		(fp_line
			(start 0.67945 0.3048)
			(end 0.67945 -0.305054)
			(stroke
				(width 0.1)
				(type default)
			)
			(layer "B.Fab")
		)
		(fp_line
			(start 0.67945 -0.305054)
			(end 0.12065 -0.305054)
			(stroke
				(width 0.1)
				(type default)
			)
			(layer "B.Fab")
		)
		(fp_line
			(start 0.12065 0.3048)
			(end 0.67945 0.3048)
			(stroke
				(width 0.1)
				(type default)
			)
			(layer "B.Fab")
		)
		(fp_line
			(start 0.12065 0.2794)
			(end 0.12065 0.3048)
			(stroke
				(width 0.1)
				(type default)
			)
			(layer "B.Fab")
		)
		(fp_line
			(start 0.12065 -0.2794)
			(end -0.12065 -0.2794)
			(stroke
				(width 0.1)
				(type default)
			)
			(layer "B.Fab")
		)
		(fp_line
			(start 0.12065 -0.305054)
			(end 0.12065 -0.2794)
			(stroke
				(width 0.1)
				(type default)
			)
			(layer "B.Fab")
		)
		(fp_line
			(start -0.120396 0.3048)
			(end -0.120396 0.2794)
			(stroke
				(width 0.1)
				(type default)
			)
			(layer "B.Fab")
		)
		(fp_line
			(start -0.120396 0.2794)
			(end 0.12065 0.2794)
			(stroke
				(width 0.1)
				(type default)
			)
			(layer "B.Fab")
		)
		(fp_line
			(start -0.12065 -0.2794)
			(end -0.12065 -0.3048)
			(stroke
				(width 0.1)
				(type default)
			)
			(layer "B.Fab")
		)
		(fp_line
			(start -0.12065 -0.3048)
			(end -0.67945 -0.3048)
			(stroke
				(width 0.1)
				(type default)
			)
			(layer "B.Fab")
		)
		(fp_line
			(start -0.67945 0.3048)
			(end -0.120396 0.3048)
			(stroke
				(width 0.1)
				(type default)
			)
			(layer "B.Fab")
		)
		(fp_line
			(start -0.67945 -0.3048)
			(end -0.67945 0.3048)
			(stroke
				(width 0.1)
				(type default)
			)
			(layer "B.Fab")
		)
		(pad "1" smd circle
			(at 0.40005 0)
			(size 0 0)
			(layers "B.Cu" "B.Mask" "B.Paste")
			(net "M_B_CPU1_ALERT_N")
		)
		(pad "2" smd circle
			(at -0.40005 0)
			(size 0 0)
			(layers "B.Cu" "B.Mask" "B.Paste")
			(net "M_B_CPU1_ALERT_R_N")
		)
	)
	(footprint ""
		(layer "B.Cu")
		(at 138.112246 -32.135318 -90)
		(property "Reference" "C6046"
			(at 0 0 90)
			(layer "B.SilkS")
			(hide yes)
			(effects
				(font
					(size 1.27 1.27)
				)
				(justify mirror)
			)
		)
		(property "Value" ""
			(at 0 0 90)
			(layer "B.Fab")
			(effects
				(font
					(size 1.27 1.27)
				)
				(justify mirror)
			)
		)
		(duplicate_pad_numbers_are_jumpers no)
		(fp_line
			(start -1.2954 0.5842)
			(end 1.2954 0.5842)
			(stroke
				(width 0.1524)
				(type default)
			)
			(layer "B.SilkS")
		)
		(fp_line
			(start 1.2954 0.5842)
			(end 1.2954 -0.5842)
			(stroke
				(width 0.1524)
				(type default)
			)
			(layer "B.SilkS")
		)
		(fp_line
			(start -1.2954 -0.5842)
			(end -1.2954 0.5842)
			(stroke
				(width 0.1524)
				(type default)
			)
			(layer "B.SilkS")
		)
		(fp_line
			(start 1.2954 -0.5842)
			(end -1.2954 -0.5842)
			(stroke
				(width 0.1524)
				(type default)
			)
			(layer "B.SilkS")
		)
		(fp_line
			(start -0.8636 0.4572)
			(end 0.8636 0.4572)
			(stroke
				(width 0.1)
				(type default)
			)
			(layer "B.Fab")
		)
		(fp_line
			(start 0.8636 0.4572)
			(end 0.8636 0.4064)
			(stroke
				(width 0.1)
				(type default)
			)
			(layer "B.Fab")
		)
		(fp_line
			(start -1.1938 0.4064)
			(end -0.8636 0.4064)
			(stroke
				(width 0.1)
				(type default)
			)
			(layer "B.Fab")
		)
		(fp_line
			(start -0.8636 0.4064)
			(end -0.8636 0.4572)
			(stroke
				(width 0.1)
				(type default)
			)
			(layer "B.Fab")
		)
		(fp_line
			(start 0.8636 0.4064)
			(end 1.1938 0.4064)
			(stroke
				(width 0.1)
				(type default)
			)
			(layer "B.Fab")
		)
		(fp_line
			(start 1.1938 0.4064)
			(end 1.1938 -0.4064)
			(stroke
				(width 0.1)
				(type default)
			)
			(layer "B.Fab")
		)
		(fp_line
			(start -1.1938 -0.4064)
			(end -1.1938 0.4064)
			(stroke
				(width 0.1)
				(type default)
			)
			(layer "B.Fab")
		)
		(fp_line
			(start -0.8636 -0.4064)
			(end -1.1938 -0.4064)
			(stroke
				(width 0.1)
				(type default)
			)
			(layer "B.Fab")
		)
		(fp_line
			(start 0.8636 -0.4064)
			(end 0.8636 -0.4572)
			(stroke
				(width 0.1)
				(type default)
			)
			(layer "B.Fab")
		)
		(fp_line
			(start 1.1938 -0.4064)
			(end 0.8636 -0.4064)
			(stroke
				(width 0.1)
				(type default)
			)
			(layer "B.Fab")
		)
		(fp_line
			(start -0.8636 -0.4572)
			(end -0.8636 -0.4064)
			(stroke
				(width 0.1)
				(type default)
			)
			(layer "B.Fab")
		)
		(fp_line
			(start 0.8636 -0.4572)
			(end -0.8636 -0.4572)
			(stroke
				(width 0.1)
				(type default)
			)
			(layer "B.Fab")
		)
		(pad "1" smd rect
			(at 0.7366 0 180)
			(size 0.7112 0.8128)
			(layers "B.Cu" "B.Mask" "B.Paste")
			(net "P3V3_AUX")
		)
		(pad "2" smd rect
			(at -0.7366 0 180)
			(size 0.7112 0.8128)
			(layers "B.Cu" "B.Mask" "B.Paste")
			(net "GND")
		)
	)
	(footprint ""
		(layer "B.Cu")
		(at 198.7042 -192.66027)
		(property "Reference" "C546"
			(at 0 0 0)
			(layer "B.SilkS")
			(hide yes)
			(effects
				(font
					(size 1.27 1.27)
				)
				(justify mirror)
			)
		)
		(property "Value" ""
			(at 0 0 0)
			(layer "B.Fab")
			(effects
				(font
					(size 1.27 1.27)
				)
				(justify mirror)
			)
		)
		(duplicate_pad_numbers_are_jumpers no)
		(fp_line
			(start -1.524 -0.762)
			(end -1.524 0.762)
			(stroke
				(width 0.1524)
				(type default)
			)
			(layer "B.SilkS")
		)
		(fp_line
			(start -1.524 0.762)
			(end 1.524 0.762)
			(stroke
				(width 0.1524)
				(type default)
			)
			(layer "B.SilkS")
		)
		(fp_line
			(start 1.524 -0.762)
			(end -1.524 -0.762)
			(stroke
				(width 0.1524)
				(type default)
			)
			(layer "B.SilkS")
		)
		(fp_line
			(start 1.524 0.762)
			(end 1.524 -0.762)
			(stroke
				(width 0.1524)
				(type default)
			)
			(layer "B.SilkS")
		)
		(fp_line
			(start -1.1049 -0.724916)
			(end 1.1049 -0.724916)
			(stroke
				(width 0.1)
				(type default)
			)
			(layer "B.Fab")
		)
		(fp_line
			(start -1.1049 0.724916)
			(end -1.1049 -0.724916)
			(stroke
				(width 0.1)
				(type default)
			)
			(layer "B.Fab")
		)
		(fp_line
			(start 1.1049 -0.724916)
			(end 1.1049 0.724916)
			(stroke
				(width 0.1)
				(type default)
			)
			(layer "B.Fab")
		)
		(fp_line
			(start 1.1049 0.724916)
			(end -1.1049 0.724916)
			(stroke
				(width 0.1)
				(type default)
			)
			(layer "B.Fab")
		)
		(pad "1" smd rect
			(at 0.889 0)
			(size 1.016 1.27)
			(layers "B.Cu" "B.Mask" "B.Paste")
			(net "P12V_MEM_CPU1")
		)
		(pad "2" smd rect
			(at -0.889 0)
			(size 1.016 1.27)
			(layers "B.Cu" "B.Mask" "B.Paste")
			(net "GND")
		)
	)
	(footprint ""
		(layer "B.Cu")
		(at 13.649452 -101.21138 90)
		(property "Reference" "C2031"
			(at 0 0 90)
			(layer "B.SilkS")
			(hide yes)
			(effects
				(font
					(size 1.27 1.27)
				)
				(justify mirror)
			)
		)
		(property "Value" ""
			(at 0 0 90)
			(layer "B.Fab")
			(effects
				(font
					(size 1.27 1.27)
				)
				(justify mirror)
			)
		)
		(duplicate_pad_numbers_are_jumpers no)
		(fp_line
			(start 0.7874 -0.4064)
			(end -0.7874 -0.4064)
			(stroke
				(width 0.1524)
				(type default)
			)
			(layer "B.SilkS")
		)
		(fp_line
			(start -0.7874 -0.4064)
			(end -0.7874 0.4064)
			(stroke
				(width 0.1524)
				(type default)
			)
			(layer "B.SilkS")
		)
		(fp_line
			(start 0.7874 0.4064)
			(end 0.7874 -0.4064)
			(stroke
				(width 0.1524)
				(type default)
			)
			(layer "B.SilkS")
		)
		(fp_line
			(start -0.7874 0.4064)
			(end 0.7874 0.4064)
			(stroke
				(width 0.1524)
				(type default)
			)
			(layer "B.SilkS")
		)
		(fp_line
			(start 0.67945 -0.305054)
			(end 0.12065 -0.305054)
			(stroke
				(width 0.1)
				(type default)
			)
			(layer "B.Fab")
		)
		(fp_line
			(start 0.12065 -0.305054)
			(end 0.12065 -0.2794)
			(stroke
				(width 0.1)
				(type default)
			)
			(layer "B.Fab")
		)
		(fp_line
			(start -0.12065 -0.3048)
			(end -0.67945 -0.3048)
			(stroke
				(width 0.1)
				(type default)
			)
			(layer "B.Fab")
		)
		(fp_line
			(start -0.67945 -0.3048)
			(end -0.67945 0.3048)
			(stroke
				(width 0.1)
				(type default)
			)
			(layer "B.Fab")
		)
		(fp_line
			(start 0.12065 -0.2794)
			(end -0.12065 -0.2794)
			(stroke
				(width 0.1)
				(type default)
			)
			(layer "B.Fab")
		)
		(fp_line
			(start -0.12065 -0.2794)
			(end -0.12065 -0.3048)
			(stroke
				(width 0.1)
				(type default)
			)
			(layer "B.Fab")
		)
		(fp_line
			(start 0.12065 0.2794)
			(end 0.12065 0.3048)
			(stroke
				(width 0.1)
				(type default)
			)
			(layer "B.Fab")
		)
		(fp_line
			(start -0.120396 0.2794)
			(end 0.12065 0.2794)
			(stroke
				(width 0.1)
				(type default)
			)
			(layer "B.Fab")
		)
		(fp_line
			(start 0.67945 0.3048)
			(end 0.67945 -0.305054)
			(stroke
				(width 0.1)
				(type default)
			)
			(layer "B.Fab")
		)
		(fp_line
			(start 0.12065 0.3048)
			(end 0.67945 0.3048)
			(stroke
				(width 0.1)
				(type default)
			)
			(layer "B.Fab")
		)
		(fp_line
			(start -0.120396 0.3048)
			(end -0.120396 0.2794)
			(stroke
				(width 0.1)
				(type default)
			)
			(layer "B.Fab")
		)
		(fp_line
			(start -0.67945 0.3048)
			(end -0.120396 0.3048)
			(stroke
				(width 0.1)
				(type default)
			)
			(layer "B.Fab")
		)
		(pad "1" smd circle
			(at 0.40005 0 270)
			(size 0 0)
			(layers "B.Cu" "B.Mask" "B.Paste")
			(net "P3V3_AUX_USB_HUB")
		)
		(pad "2" smd circle
			(at -0.40005 0 270)
			(size 0 0)
			(layers "B.Cu" "B.Mask" "B.Paste")
			(net "GND")
		)
	)
	(footprint ""
		(layer "B.Cu")
		(at 106.352848 -178.110134 -90)
		(property "Reference" "PC299_4"
			(at 0 0 90)
			(layer "B.SilkS")
			(hide yes)
			(effects
				(font
					(size 1.27 1.27)
				)
				(justify mirror)
			)
		)
		(property "Value" ""
			(at 0 0 90)
			(layer "B.Fab")
			(effects
				(font
					(size 1.27 1.27)
				)
				(justify mirror)
			)
		)
		(duplicate_pad_numbers_are_jumpers no)
		(fp_line
			(start -1.524 0.762)
			(end 1.524 0.762)
			(stroke
				(width 0.1524)
				(type default)
			)
			(layer "B.SilkS")
		)
		(fp_line
			(start 1.524 0.762)
			(end 1.524 -0.762)
			(stroke
				(width 0.1524)
				(type default)
			)
			(layer "B.SilkS")
		)
		(fp_line
			(start -1.524 -0.762)
			(end -1.524 0.762)
			(stroke
				(width 0.1524)
				(type default)
			)
			(layer "B.SilkS")
		)
		(fp_line
			(start 1.524 -0.762)
			(end -1.524 -0.762)
			(stroke
				(width 0.1524)
				(type default)
			)
			(layer "B.SilkS")
		)
		(fp_line
			(start -1.1049 0.724916)
			(end -1.1049 -0.724916)
			(stroke
				(width 0.1)
				(type default)
			)
			(layer "B.Fab")
		)
		(fp_line
			(start 1.1049 0.724916)
			(end -1.1049 0.724916)
			(stroke
				(width 0.1)
				(type default)
			)
			(layer "B.Fab")
		)
		(fp_line
			(start -1.1049 -0.724916)
			(end 1.1049 -0.724916)
			(stroke
				(width 0.1)
				(type default)
			)
			(layer "B.Fab")
		)
		(fp_line
			(start 1.1049 -0.724916)
			(end 1.1049 0.724916)
			(stroke
				(width 0.1)
				(type default)
			)
			(layer "B.Fab")
		)
		(pad "1" smd rect
			(at 0.889 0 270)
			(size 1.016 1.27)
			(layers "B.Cu" "B.Mask" "B.Paste")
			(net "SW_P12V_AUX_PVDDCR_CPU0_P1_FLT")
		)
		(pad "2" smd rect
			(at -0.889 0 270)
			(size 1.016 1.27)
			(layers "B.Cu" "B.Mask" "B.Paste")
			(net "GND")
		)
	)
	(footprint ""
		(layer "B.Cu")
		(at 343.118694 -398.942052 90)
		(property "Reference" "C646"
			(at 0 0 90)
			(layer "B.SilkS")
			(hide yes)
			(effects
				(font
					(size 1.27 1.27)
				)
				(justify mirror)
			)
		)
		(property "Value" ""
			(at 0 0 90)
			(layer "B.Fab")
			(effects
				(font
					(size 1.27 1.27)
				)
				(justify mirror)
			)
		)
		(duplicate_pad_numbers_are_jumpers no)
		(fp_line
			(start 0.7874 -0.4064)
			(end -0.7874 -0.4064)
			(stroke
				(width 0.1524)
				(type default)
			)
			(layer "B.SilkS")
		)
		(fp_line
			(start -0.7874 -0.4064)
			(end -0.7874 0.4064)
			(stroke
				(width 0.1524)
				(type default)
			)
			(layer "B.SilkS")
		)
		(fp_line
			(start 0.7874 0.4064)
			(end 0.7874 -0.4064)
			(stroke
				(width 0.1524)
				(type default)
			)
			(layer "B.SilkS")
		)
		(fp_line
			(start -0.7874 0.4064)
			(end 0.7874 0.4064)
			(stroke
				(width 0.1524)
				(type default)
			)
			(layer "B.SilkS")
		)
		(fp_line
			(start 0.67945 -0.305054)
			(end 0.12065 -0.305054)
			(stroke
				(width 0.1)
				(type default)
			)
			(layer "B.Fab")
		)
		(fp_line
			(start 0.12065 -0.305054)
			(end 0.12065 -0.2794)
			(stroke
				(width 0.1)
				(type default)
			)
			(layer "B.Fab")
		)
		(fp_line
			(start -0.12065 -0.3048)
			(end -0.67945 -0.3048)
			(stroke
				(width 0.1)
				(type default)
			)
			(layer "B.Fab")
		)
		(fp_line
			(start -0.67945 -0.3048)
			(end -0.67945 0.3048)
			(stroke
				(width 0.1)
				(type default)
			)
			(layer "B.Fab")
		)
		(fp_line
			(start 0.12065 -0.2794)
			(end -0.12065 -0.2794)
			(stroke
				(width 0.1)
				(type default)
			)
			(layer "B.Fab")
		)
		(fp_line
			(start -0.12065 -0.2794)
			(end -0.12065 -0.3048)
			(stroke
				(width 0.1)
				(type default)
			)
			(layer "B.Fab")
		)
		(fp_line
			(start 0.12065 0.2794)
			(end 0.12065 0.3048)
			(stroke
				(width 0.1)
				(type default)
			)
			(layer "B.Fab")
		)
		(fp_line
			(start -0.120396 0.2794)
			(end 0.12065 0.2794)
			(stroke
				(width 0.1)
				(type default)
			)
			(layer "B.Fab")
		)
		(fp_line
			(start 0.67945 0.3048)
			(end 0.67945 -0.305054)
			(stroke
				(width 0.1)
				(type default)
			)
			(layer "B.Fab")
		)
		(fp_line
			(start 0.12065 0.3048)
			(end 0.67945 0.3048)
			(stroke
				(width 0.1)
				(type default)
			)
			(layer "B.Fab")
		)
		(fp_line
			(start -0.120396 0.3048)
			(end -0.120396 0.2794)
			(stroke
				(width 0.1)
				(type default)
			)
			(layer "B.Fab")
		)
		(fp_line
			(start -0.67945 0.3048)
			(end -0.120396 0.3048)
			(stroke
				(width 0.1)
				(type default)
			)
			(layer "B.Fab")
		)
		(pad "1" smd circle
			(at 0.40005 0 270)
			(size 0 0)
			(layers "B.Cu" "B.Mask" "B.Paste")
			(net "P0V9_CPU0_RT_2D")
		)
		(pad "2" smd circle
			(at -0.40005 0 270)
			(size 0 0)
			(layers "B.Cu" "B.Mask" "B.Paste")
			(net "GND")
		)
	)
	(footprint ""
		(layer "B.Cu")
		(at 214.122 -335.026)
		(property "Reference" "R6812"
			(at 0 0 0)
			(layer "B.SilkS")
			(hide yes)
			(effects
				(font
					(size 1.27 1.27)
				)
				(justify mirror)
			)
		)
		(property "Value" ""
			(at 0 0 0)
			(layer "B.Fab")
			(effects
				(font
					(size 1.27 1.27)
				)
				(justify mirror)
			)
		)
		(duplicate_pad_numbers_are_jumpers no)
		(fp_line
			(start -0.32512 -0.175006)
			(end -0.32512 0.175006)
			(stroke
				(width 0.1)
				(type default)
			)
			(layer "B.Fab")
		)
		(fp_line
			(start -0.32512 0.175006)
			(end 0.32512 0.175006)
			(stroke
				(width 0.1)
				(type default)
			)
			(layer "B.Fab")
		)
		(fp_line
			(start 0.32512 -0.175006)
			(end -0.32512 -0.175006)
			(stroke
				(width 0.1)
				(type default)
			)
			(layer "B.Fab")
		)
		(fp_line
			(start 0.32512 0.175006)
			(end 0.32512 -0.175006)
			(stroke
				(width 0.1)
				(type default)
			)
			(layer "B.Fab")
		)
		(pad "1" smd rect
			(at 0.2667 0 180)
			(size 0.3048 0.381)
			(layers "B.Cu" "B.Mask" "B.Paste")
			(net "SMB_RT_CPU1_P0_R_SCL")
		)
		(pad "2" smd rect
			(at -0.2667 0)
			(size 0.3048 0.381)
			(layers "B.Cu" "B.Mask" "B.Paste")
			(net "SMB_RT_CPU1_P0_R2_SCL")
		)
	)
)
